(kicad_pcb
	(version 20260206)
	(generator "pcbnew")
	(generator_version "10.0")
	(general
		(thickness 1.6)
		(legacy_teardrops no)
	)
	(paper "A4")
	(title_block
		(title "v2-pdb — ms_pdb_v2.brd")
		(comment 1 "Open CloudServer (Microsoft) / footprints 283-291 of 348")
	)
	(layers
		(0 "F.Cu" signal "TOP")
		(4 "In1.Cu" signal "GND")
		(6 "In2.Cu" signal "IN1")
		(8 "In3.Cu" signal "VCC")
		(10 "In4.Cu" signal "VCC1")
		(12 "In5.Cu" signal "IN2")
		(14 "In6.Cu" signal "GND1")
		(2 "B.Cu" signal "BOTTOM")
		(9 "F.Adhes" user "F.Adhesive")
		(11 "B.Adhes" user "B.Adhesive")
		(13 "F.Paste" user "Package Geometry/Pastemask Top")
		(15 "B.Paste" user "Package Geometry/Pastemask Bottom")
		(5 "F.SilkS" user "Ref Des/Silkscreen Top")
		(7 "B.SilkS" user "Ref Des/Silkscreen Bottom")
		(1 "F.Mask" user "Board Geometry/Soldermask Top")
		(3 "B.Mask" user "Board Geometry/Soldermask Bottom")
		(17 "Dwgs.User" user "User.Drawings")
		(19 "Cmts.User" user "User.Comments")
		(21 "Eco1.User" user "User.Eco1")
		(23 "Eco2.User" user "User.Eco2")
		(25 "Edge.Cuts" user "Board Geometry/Outline")
		(27 "Margin" user)
		(31 "F.CrtYd" user "Package Geometry/Place Bound Top")
		(29 "B.CrtYd" user "Package Geometry/Place Bound Bottom")
		(35 "F.Fab" user "Ref Des/Assembly Top")
		(33 "B.Fab" user "Ref Des/Assembly Bottom")
	)
	(footprint ""
		(layer "F.Cu")
		(at 77.999844 -341.250016)
		(property "Reference" "H5"
			(at -6.4516 -7.127748 0)
			(unlocked yes)
			(layer "F.SilkS")
			(effects
				(font
					(size 0.7874 0.5842)
					(thickness 0.1524)
				)
				(justify left)
			)
		)
		(property "Value" ""
			(at 0 0 0)
			(layer "F.Fab")
			(effects
				(font
					(size 1.27 1.27)
				)
			)
		)
		(duplicate_pad_numbers_are_jumpers no)
		(fp_circle
			(center 0 0)
			(end 7.999984 0)
			(stroke
				(width 0.1524)
				(type default)
			)
			(fill no)
			(layer "F.SilkS")
		)
		(fp_circle
			(center 0 0)
			(end 14.7066 0)
			(stroke
				(width 0.1524)
				(type default)
			)
			(fill no)
			(layer "B.SilkS")
		)
		(fp_poly
			(pts
				(arc
					(start 5.0038 0)
					(mid -5.0038 0)
					(end 5.0038 0)
				)
			)
			(stroke
				(width 0)
				(type default)
			)
			(fill no)
			(layer "F.CrtYd")
		)
		(pad "" np_thru_hole circle
			(at 0 0)
			(size 4.0132 4.0132)
			(drill 4.0132)
			(layers "*.Cu" "*.Mask")
			(clearance 0.381)
			(thermal_gap 0.381)
		)
		(pad "2" thru_hole circle
			(at 0 -3.50012)
			(size 0.762 0.762)
			(drill 0.5588)
			(layers "*.Cu" "*.Mask")
			(remove_unused_layers no)
			(net "GND")
			(clearance 0.1524)
			(thermal_gap 0.1524)
		)
		(pad "3" thru_hole circle
			(at -2.500122 -2.500122)
			(size 0.762 0.762)
			(drill 0.5588)
			(layers "*.Cu" "*.Mask")
			(remove_unused_layers no)
			(net "GND")
			(clearance 0.1524)
			(thermal_gap 0.1524)
		)
		(pad "4" thru_hole circle
			(at -3.50012 0)
			(size 0.762 0.762)
			(drill 0.5588)
			(layers "*.Cu" "*.Mask")
			(remove_unused_layers no)
			(net "GND")
			(clearance 0.1524)
			(thermal_gap 0.1524)
		)
		(pad "5" thru_hole circle
			(at -2.500122 2.500122)
			(size 0.762 0.762)
			(drill 0.5588)
			(layers "*.Cu" "*.Mask")
			(remove_unused_layers no)
			(net "GND")
			(clearance 0.1524)
			(thermal_gap 0.1524)
		)
		(pad "6" thru_hole circle
			(at 0 3.50012)
			(size 0.762 0.762)
			(drill 0.5588)
			(layers "*.Cu" "*.Mask")
			(remove_unused_layers no)
			(net "GND")
			(clearance 0.1524)
			(thermal_gap 0.1524)
		)
		(pad "7" thru_hole circle
			(at 2.500122 2.500122)
			(size 0.762 0.762)
			(drill 0.5588)
			(layers "*.Cu" "*.Mask")
			(remove_unused_layers no)
			(net "GND")
			(clearance 0.1524)
			(thermal_gap 0.1524)
		)
		(pad "8" thru_hole circle
			(at 3.50012 0)
			(size 0.762 0.762)
			(drill 0.5588)
			(layers "*.Cu" "*.Mask")
			(remove_unused_layers no)
			(net "GND")
			(clearance 0.1524)
			(thermal_gap 0.1524)
		)
		(pad "9" thru_hole circle
			(at 2.500122 -2.500122)
			(size 0.762 0.762)
			(drill 0.5588)
			(layers "*.Cu" "*.Mask")
			(remove_unused_layers no)
			(net "GND")
			(clearance 0.1524)
			(thermal_gap 0.1524)
		)
		(zone
			(layer "F.Cu")
			(hatch none 0.5)
			(connect_pads
				(clearance 0)
			)
			(min_thickness 0.25)
			(keepout
				(tracks not_allowed)
				(vias allowed)
				(pads allowed)
				(copperpour not_allowed)
				(footprints allowed)
			)
			(placement
				(enabled no)
				(sheetname "")
			)
			(fill
				(thermal_gap 0.5)
				(thermal_bridge_width 0.5)
				(island_removal_mode 0)
			)
			(polygon
				(pts
					(arc
						(start 77.999844 -349.251016)
						(mid 69.998844 -341.250016)
						(end 77.999844 -333.249016)
					)
					(arc
						(start 77.999844 -333.249016)
						(mid 79.434944 -334.684116)
						(end 77.999844 -336.119216)
					)
					(arc
						(start 77.999844 -336.119216)
						(mid 72.869044 -341.250016)
						(end 77.999844 -346.380816)
					)
					(arc
						(start 77.999844 -346.380816)
						(mid 79.434944 -347.815916)
						(end 77.999844 -349.251016)
					)
				)
			)
		)
		(zone
			(layer "F.Cu")
			(hatch none 0.5)
			(connect_pads
				(clearance 0)
			)
			(min_thickness 0.25)
			(keepout
				(tracks not_allowed)
				(vias allowed)
				(pads allowed)
				(copperpour not_allowed)
				(footprints allowed)
			)
			(placement
				(enabled no)
				(sheetname "")
			)
			(fill
				(thermal_gap 0.5)
				(thermal_bridge_width 0.5)
				(island_removal_mode 0)
			)
			(polygon
				(pts
					(arc
						(start 77.999844 -349.251016)
						(mid 86.000844 -341.250016)
						(end 77.999844 -333.249016)
					)
					(arc
						(start 77.999844 -333.249016)
						(mid 76.564744 -334.684116)
						(end 77.999844 -336.119216)
					)
					(arc
						(start 77.999844 -336.119216)
						(mid 83.130644 -341.250016)
						(end 77.999844 -346.380816)
					)
					(arc
						(start 77.999844 -346.380816)
						(mid 76.564744 -347.815916)
						(end 77.999844 -349.251016)
					)
				)
			)
		)
		(zone
			(layers "F.Cu" "B.Cu" "In1.Cu" "In2.Cu" "In3.Cu" "In4.Cu" "In5.Cu" "In6.Cu")
			(hatch none 0.5)
			(connect_pads
				(clearance 0)
			)
			(min_thickness 0.25)
			(keepout
				(tracks not_allowed)
				(vias allowed)
				(pads allowed)
				(copperpour not_allowed)
				(footprints allowed)
			)
			(placement
				(enabled no)
				(sheetname "")
			)
			(fill
				(thermal_gap 0.5)
				(thermal_bridge_width 0.5)
				(island_removal_mode 0)
			)
			(polygon
				(pts
					(arc
						(start 80.511904 -341.250016)
						(mid 75.487784 -341.250016)
						(end 80.511904 -341.250016)
					)
				)
			)
		)
	)
	(footprint ""
		(layer "F.Cu")
		(at 91.399868 -153.359866)
		(property "Reference" "H22"
			(at -5.1308 -5.23113 0)
			(unlocked yes)
			(layer "F.SilkS")
			(effects
				(font
					(size 0.7874 0.5842)
					(thickness 0.1524)
				)
				(justify left)
			)
		)
		(property "Value" ""
			(at 0 0 0)
			(layer "F.Fab")
			(effects
				(font
					(size 1.27 1.27)
				)
			)
		)
		(duplicate_pad_numbers_are_jumpers no)
		(fp_circle
			(center 0 0)
			(end 4.826 0)
			(stroke
				(width 0.1524)
				(type default)
			)
			(fill no)
			(layer "F.SilkS")
		)
		(fp_circle
			(center 0 0)
			(end 4.826 0)
			(stroke
				(width 0.1524)
				(type default)
			)
			(fill no)
			(layer "B.SilkS")
		)
		(fp_poly
			(pts
				(arc
					(start 0 4.0132)
					(mid 0 -4.0132)
					(end 0 4.0132)
				)
			)
			(stroke
				(width 0)
				(type default)
			)
			(fill no)
			(layer "F.CrtYd")
		)
		(pad "" np_thru_hole circle
			(at 0 0)
			(size 8.001 8.001)
			(drill 8.001)
			(layers "*.Cu" "*.Mask")
			(clearance 0.381)
			(thermal_gap 0.381)
		)
		(zone
			(layers "F.Cu" "B.Cu" "In1.Cu" "In2.Cu" "In3.Cu" "In4.Cu" "In5.Cu" "In6.Cu")
			(hatch none 0.5)
			(connect_pads
				(clearance 0)
			)
			(min_thickness 0.25)
			(keepout
				(tracks not_allowed)
				(vias allowed)
				(pads allowed)
				(copperpour not_allowed)
				(footprints allowed)
			)
			(placement
				(enabled no)
				(sheetname "")
			)
			(fill
				(thermal_gap 0.5)
				(thermal_bridge_width 0.5)
				(island_removal_mode 0)
			)
			(polygon
				(pts
					(arc
						(start 91.399868 -148.838666)
						(mid 91.399868 -157.881066)
						(end 91.399868 -148.838666)
					)
				)
			)
		)
	)
	(footprint ""
		(layer "F.Cu")
		(at 15.509748 -452.87819 180)
		(property "Reference" "R154"
			(at 1.36779 3.459226 0)
			(unlocked yes)
			(layer "F.SilkS")
			(effects
				(font
					(size 0.7874 0.5842)
					(thickness 0.1524)
				)
				(justify left)
			)
		)
		(property "Value" ""
			(at 0 0 180)
			(layer "F.Fab")
			(effects
				(font
					(size 1.27 1.27)
				)
			)
		)
		(duplicate_pad_numbers_are_jumpers no)
		(fp_line
			(start 0.7874 0.4064)
			(end -0.7874 0.4064)
			(stroke
				(width 0.1524)
				(type default)
			)
			(layer "F.SilkS")
		)
		(fp_line
			(start 0.7874 -0.4064)
			(end 0.7874 0.4064)
			(stroke
				(width 0.1524)
				(type default)
			)
			(layer "F.SilkS")
		)
		(fp_line
			(start -0.7874 0.4064)
			(end -0.7874 -0.4064)
			(stroke
				(width 0.1524)
				(type default)
			)
			(layer "F.SilkS")
		)
		(fp_line
			(start -0.7874 -0.4064)
			(end 0.7874 -0.4064)
			(stroke
				(width 0.1524)
				(type default)
			)
			(layer "F.SilkS")
		)
		(fp_poly
			(pts
				(xy -0.508 0.2794) (xy -0.508 0.2286) (xy -0.635 0.2286) (xy -0.635 -0.254) (xy -0.5334 -0.254)
				(xy -0.5334 -0.2794) (xy 0.5334 -0.2794) (xy 0.5334 -0.254) (xy 0.635 -0.254) (xy 0.635 0.254) (xy 0.5334 0.254)
				(xy 0.5334 0.2794)
			)
			(stroke
				(width 0)
				(type default)
			)
			(fill no)
			(layer "F.CrtYd")
		)
		(pad "1" smd rect
			(at 0.40005 0 180)
			(size 0.4572 0.508)
			(layers "F.Cu" "F.Mask" "F.Paste")
			(net "P12V")
		)
		(pad "2" smd rect
			(at -0.40005 0 180)
			(size 0.4572 0.508)
			(layers "F.Cu" "F.Mask" "F.Paste")
			(net "N42241895")
		)
	)
	(footprint ""
		(layer "F.Cu")
		(at 80.932782 -295.215564 180)
		(property "Reference" "R124"
			(at 1.303528 -1.245108 0)
			(unlocked yes)
			(layer "F.SilkS")
			(effects
				(font
					(size 0.7874 0.5842)
					(thickness 0.1524)
				)
				(justify left)
			)
		)
		(property "Value" ""
			(at 0 0 180)
			(layer "F.Fab")
			(effects
				(font
					(size 1.27 1.27)
				)
			)
		)
		(duplicate_pad_numbers_are_jumpers no)
		(fp_line
			(start 0.7874 0.4064)
			(end -0.7874 0.4064)
			(stroke
				(width 0.1524)
				(type default)
			)
			(layer "F.SilkS")
		)
		(fp_line
			(start 0.7874 -0.4064)
			(end 0.7874 0.4064)
			(stroke
				(width 0.1524)
				(type default)
			)
			(layer "F.SilkS")
		)
		(fp_line
			(start -0.7874 0.4064)
			(end -0.7874 -0.4064)
			(stroke
				(width 0.1524)
				(type default)
			)
			(layer "F.SilkS")
		)
		(fp_line
			(start -0.7874 -0.4064)
			(end 0.7874 -0.4064)
			(stroke
				(width 0.1524)
				(type default)
			)
			(layer "F.SilkS")
		)
		(fp_poly
			(pts
				(xy -0.508 0.2794) (xy -0.508 0.2286) (xy -0.635 0.2286) (xy -0.635 -0.254) (xy -0.5334 -0.254)
				(xy -0.5334 -0.2794) (xy 0.5334 -0.2794) (xy 0.5334 -0.254) (xy 0.635 -0.254) (xy 0.635 0.254) (xy 0.5334 0.254)
				(xy 0.5334 0.2794)
			)
			(stroke
				(width 0)
				(type default)
			)
			(fill no)
			(layer "F.CrtYd")
		)
		(pad "1" smd rect
			(at 0.40005 0 180)
			(size 0.4572 0.508)
			(layers "F.Cu" "F.Mask" "F.Paste")
			(net "PSU4_REMOTE_R2_N")
		)
		(pad "2" smd rect
			(at -0.40005 0 180)
			(size 0.4572 0.508)
			(layers "F.Cu" "F.Mask" "F.Paste")
			(net "GND")
		)
	)
	(footprint ""
		(layer "F.Cu")
		(at 25.997662 -7.19328)
		(property "Reference" "R62"
			(at -3.764788 0.113792 0)
			(unlocked yes)
			(layer "F.SilkS")
			(effects
				(font
					(size 0.7874 0.5842)
					(thickness 0.1524)
				)
				(justify left)
			)
		)
		(property "Value" ""
			(at 0 0 0)
			(layer "F.Fab")
			(effects
				(font
					(size 1.27 1.27)
				)
			)
		)
		(duplicate_pad_numbers_are_jumpers no)
		(fp_line
			(start -0.7874 -0.4064)
			(end 0.7874 -0.4064)
			(stroke
				(width 0.1524)
				(type default)
			)
			(layer "F.SilkS")
		)
		(fp_line
			(start -0.7874 0.4064)
			(end -0.7874 -0.4064)
			(stroke
				(width 0.1524)
				(type default)
			)
			(layer "F.SilkS")
		)
		(fp_line
			(start 0.7874 -0.4064)
			(end 0.7874 0.4064)
			(stroke
				(width 0.1524)
				(type default)
			)
			(layer "F.SilkS")
		)
		(fp_line
			(start 0.7874 0.4064)
			(end -0.7874 0.4064)
			(stroke
				(width 0.1524)
				(type default)
			)
			(layer "F.SilkS")
		)
		(fp_poly
			(pts
				(xy -0.508 0.2794) (xy -0.508 0.2286) (xy -0.635 0.2286) (xy -0.635 -0.254) (xy -0.5334 -0.254)
				(xy -0.5334 -0.2794) (xy 0.5334 -0.2794) (xy 0.5334 -0.254) (xy 0.635 -0.254) (xy 0.635 0.254) (xy 0.5334 0.254)
				(xy 0.5334 0.2794)
			)
			(stroke
				(width 0)
				(type default)
			)
			(fill no)
			(layer "F.CrtYd")
		)
		(pad "1" smd rect
			(at 0.40005 0)
			(size 0.4572 0.508)
			(layers "F.Cu" "F.Mask" "F.Paste")
			(net "PSU1_PS_KILL")
		)
		(pad "2" smd rect
			(at -0.40005 0)
			(size 0.4572 0.508)
			(layers "F.Cu" "F.Mask" "F.Paste")
			(net "P12V_STBY")
		)
	)
	(footprint ""
		(layer "F.Cu")
		(at 25.976072 -6.147562)
		(property "Reference" "R64"
			(at -3.764788 0.113792 0)
			(unlocked yes)
			(layer "F.SilkS")
			(effects
				(font
					(size 0.7874 0.5842)
					(thickness 0.1524)
				)
				(justify left)
			)
		)
		(property "Value" ""
			(at 0 0 0)
			(layer "F.Fab")
			(effects
				(font
					(size 1.27 1.27)
				)
			)
		)
		(duplicate_pad_numbers_are_jumpers no)
		(fp_line
			(start -0.7874 -0.4064)
			(end 0.7874 -0.4064)
			(stroke
				(width 0.1524)
				(type default)
			)
			(layer "F.SilkS")
		)
		(fp_line
			(start -0.7874 0.4064)
			(end -0.7874 -0.4064)
			(stroke
				(width 0.1524)
				(type default)
			)
			(layer "F.SilkS")
		)
		(fp_line
			(start 0.7874 -0.4064)
			(end 0.7874 0.4064)
			(stroke
				(width 0.1524)
				(type default)
			)
			(layer "F.SilkS")
		)
		(fp_line
			(start 0.7874 0.4064)
			(end -0.7874 0.4064)
			(stroke
				(width 0.1524)
				(type default)
			)
			(layer "F.SilkS")
		)
		(fp_poly
			(pts
				(xy -0.508 0.2794) (xy -0.508 0.2286) (xy -0.635 0.2286) (xy -0.635 -0.254) (xy -0.5334 -0.254)
				(xy -0.5334 -0.2794) (xy 0.5334 -0.2794) (xy 0.5334 -0.254) (xy 0.635 -0.254) (xy 0.635 0.254) (xy 0.5334 0.254)
				(xy 0.5334 0.2794)
			)
			(stroke
				(width 0)
				(type default)
			)
			(fill no)
			(layer "F.CrtYd")
		)
		(pad "1" smd rect
			(at 0.40005 0)
			(size 0.4572 0.508)
			(layers "F.Cu" "F.Mask" "F.Paste")
			(net "PSU1_RESET")
		)
		(pad "2" smd rect
			(at -0.40005 0)
			(size 0.4572 0.508)
			(layers "F.Cu" "F.Mask" "F.Paste")
			(net "P12V_STBY")
		)
	)
	(footprint ""
		(layer "F.Cu")
		(at 45.911008 -261.777988 180)
		(property "Reference" "R104"
			(at 4.5974 0.054356 0)
			(unlocked yes)
			(layer "F.SilkS")
			(effects
				(font
					(size 0.7874 0.5842)
					(thickness 0.1524)
				)
				(justify left)
			)
		)
		(property "Value" ""
			(at 0 0 180)
			(layer "F.Fab")
			(effects
				(font
					(size 1.27 1.27)
				)
			)
		)
		(duplicate_pad_numbers_are_jumpers no)
		(fp_line
			(start 0.7874 0.4064)
			(end -0.7874 0.4064)
			(stroke
				(width 0.1524)
				(type default)
			)
			(layer "F.SilkS")
		)
		(fp_line
			(start 0.7874 -0.4064)
			(end 0.7874 0.4064)
			(stroke
				(width 0.1524)
				(type default)
			)
			(layer "F.SilkS")
		)
		(fp_line
			(start -0.7874 0.4064)
			(end -0.7874 -0.4064)
			(stroke
				(width 0.1524)
				(type default)
			)
			(layer "F.SilkS")
		)
		(fp_line
			(start -0.7874 -0.4064)
			(end 0.7874 -0.4064)
			(stroke
				(width 0.1524)
				(type default)
			)
			(layer "F.SilkS")
		)
		(fp_poly
			(pts
				(xy -0.508 0.2794) (xy -0.508 0.2286) (xy -0.635 0.2286) (xy -0.635 -0.254) (xy -0.5334 -0.254)
				(xy -0.5334 -0.2794) (xy 0.5334 -0.2794) (xy 0.5334 -0.254) (xy 0.635 -0.254) (xy 0.635 0.254) (xy 0.5334 0.254)
				(xy 0.5334 0.2794)
			)
			(stroke
				(width 0)
				(type default)
			)
			(fill no)
			(layer "F.CrtYd")
		)
		(pad "1" smd rect
			(at 0.40005 0 180)
			(size 0.4572 0.508)
			(layers "F.Cu" "F.Mask" "F.Paste")
			(net "PSU5_REMOTE_R_P")
		)
		(pad "2" smd rect
			(at -0.40005 0 180)
			(size 0.4572 0.508)
			(layers "F.Cu" "F.Mask" "F.Paste")
			(net "P12V")
		)
	)
	(footprint ""
		(layer "F.Cu")
		(at 27.05481 -11.75639 180)
		(property "Reference" "R49"
			(at 3.972306 0.169926 0)
			(unlocked yes)
			(layer "F.SilkS")
			(effects
				(font
					(size 0.7874 0.5842)
					(thickness 0.1524)
				)
				(justify left)
			)
		)
		(property "Value" ""
			(at 0 0 180)
			(layer "F.Fab")
			(effects
				(font
					(size 1.27 1.27)
				)
			)
		)
		(duplicate_pad_numbers_are_jumpers no)
		(fp_line
			(start 0.7874 0.4064)
			(end -0.7874 0.4064)
			(stroke
				(width 0.1524)
				(type default)
			)
			(layer "F.SilkS")
		)
		(fp_line
			(start 0.7874 -0.4064)
			(end 0.7874 0.4064)
			(stroke
				(width 0.1524)
				(type default)
			)
			(layer "F.SilkS")
		)
		(fp_line
			(start -0.7874 0.4064)
			(end -0.7874 -0.4064)
			(stroke
				(width 0.1524)
				(type default)
			)
			(layer "F.SilkS")
		)
		(fp_line
			(start -0.7874 -0.4064)
			(end 0.7874 -0.4064)
			(stroke
				(width 0.1524)
				(type default)
			)
			(layer "F.SilkS")
		)
		(fp_poly
			(pts
				(xy -0.508 0.2794) (xy -0.508 0.2286) (xy -0.635 0.2286) (xy -0.635 -0.254) (xy -0.5334 -0.254)
				(xy -0.5334 -0.2794) (xy 0.5334 -0.2794) (xy 0.5334 -0.254) (xy 0.635 -0.254) (xy 0.635 0.254) (xy 0.5334 0.254)
				(xy 0.5334 0.2794)
			)
			(stroke
				(width 0)
				(type default)
			)
			(fill no)
			(layer "F.CrtYd")
		)
		(pad "1" smd rect
			(at 0.40005 0 180)
			(size 0.4572 0.508)
			(layers "F.Cu" "F.Mask" "F.Paste")
			(net "GND")
		)
		(pad "2" smd rect
			(at -0.40005 0 180)
			(size 0.4572 0.508)
			(layers "F.Cu" "F.Mask" "F.Paste")
			(net "PSU1_PS_ON_N")
		)
	)
	(footprint ""
		(layer "F.Cu")
		(at 25.931622 -95.65132)
		(property "Reference" "R47"
			(at -4.080256 -0.075692 0)
			(unlocked yes)
			(layer "F.SilkS")
			(effects
				(font
					(size 0.7874 0.5842)
					(thickness 0.1524)
				)
				(justify left)
			)
		)
		(property "Value" ""
			(at 0 0 0)
			(layer "F.Fab")
			(effects
				(font
					(size 1.27 1.27)
				)
			)
		)
		(duplicate_pad_numbers_are_jumpers no)
		(fp_line
			(start -0.7874 -0.4064)
			(end 0.7874 -0.4064)
			(stroke
				(width 0.1524)
				(type default)
			)
			(layer "F.SilkS")
		)
		(fp_line
			(start -0.7874 0.4064)
			(end -0.7874 -0.4064)
			(stroke
				(width 0.1524)
				(type default)
			)
			(layer "F.SilkS")
		)
		(fp_line
			(start 0.7874 -0.4064)
			(end 0.7874 0.4064)
			(stroke
				(width 0.1524)
				(type default)
			)
			(layer "F.SilkS")
		)
		(fp_line
			(start 0.7874 0.4064)
			(end -0.7874 0.4064)
			(stroke
				(width 0.1524)
				(type default)
			)
			(layer "F.SilkS")
		)
		(fp_poly
			(pts
				(xy -0.508 0.2794) (xy -0.508 0.2286) (xy -0.635 0.2286) (xy -0.635 -0.254) (xy -0.5334 -0.254)
				(xy -0.5334 -0.2794) (xy 0.5334 -0.2794) (xy 0.5334 -0.254) (xy 0.635 -0.254) (xy 0.635 0.254) (xy 0.5334 0.254)
				(xy 0.5334 0.2794)
			)
			(stroke
				(width 0)
				(type default)
			)
			(fill no)
			(layer "F.CrtYd")
		)
		(pad "1" smd rect
			(at 0.40005 0)
			(size 0.4572 0.508)
			(layers "F.Cu" "F.Mask" "F.Paste")
			(net "PSU2_RESET")
		)
		(pad "2" smd rect
			(at -0.40005 0)
			(size 0.4572 0.508)
			(layers "F.Cu" "F.Mask" "F.Paste")
			(net "GND")
		)
	)
)
